(kicad_pcb
	(version 20260206)
	(generator "pcbnew")
	(generator_version "10.0")
	(general
		(thickness 1.6)
		(legacy_teardrops no)
	)
	(paper "A4")
	(title_block
		(title "Bryce Canyon_F.DPB_16315-1-OCP.brd")
		(comment 1 "Bryce Canyon / footprints 1601-1605 of 2223")
	)
	(layers
		(0 "F.Cu" signal "TOP")
		(4 "In1.Cu" signal "L2GND")
		(6 "In2.Cu" signal "L3")
		(8 "In3.Cu" signal "L4GND")
		(10 "In4.Cu" signal "L5")
		(12 "In5.Cu" signal "L6VCC")
		(14 "In6.Cu" signal "L7VCC")
		(16 "In7.Cu" signal "L8")
		(18 "In8.Cu" signal "L9GND")
		(20 "In9.Cu" signal "L10")
		(22 "In10.Cu" signal "L11GND")
		(2 "B.Cu" signal "BOTTOM")
		(9 "F.Adhes" user "F.Adhesive")
		(11 "B.Adhes" user "B.Adhesive")
		(13 "F.Paste" user "Package Geometry/Pastemask Top")
		(15 "B.Paste" user "Package Geometry/Pastemask Bottom")
		(5 "F.SilkS" user "Ref Des/Silkscreen Top")
		(7 "B.SilkS" user "Ref Des/Silkscreen Bottom")
		(1 "F.Mask" user "Board Geometry/Soldermask Top")
		(3 "B.Mask" user "Board Geometry/Soldermask Bottom")
		(17 "Dwgs.User" user "User.Drawings")
		(19 "Cmts.User" user "User.Comments")
		(21 "Eco1.User" user "User.Eco1")
		(23 "Eco2.User" user "User.Eco2")
		(25 "Edge.Cuts" user "Board Geometry/Outline")
		(27 "Margin" user)
		(31 "F.CrtYd" user "Package Geometry/Place Bound Top")
		(29 "B.CrtYd" user "Package Geometry/Place Bound Bottom")
		(35 "F.Fab" user "Ref Des/Assembly Top")
		(33 "B.Fab" user "Ref Des/Assembly Bottom")
	)
	(footprint ""
		(layer "F.Cu")
		(at 257.4036 -290.195)
		(property "Reference" "R8"
			(at 0 0 0)
			(layer "F.SilkS")
			(hide yes)
			(effects
				(font
					(size 1.27 1.27)
				)
			)
		)
		(property "Value" "4K7R2F-GP"
			(at 0.064008 -3.993896 0)
			(unlocked yes)
			(layer "F.Fab")
			(hide yes)
			(effects
				(font
					(size 1.016 1.016)
					(thickness 0.1524)
				)
			)
		)
		(property "Device Type" "R402H16"
			(at 0.064008 -5.517896 0)
			(unlocked yes)
			(layer "F.Fab")
			(hide yes)
			(effects
				(font
					(size 1.016 1.016)
					(thickness 0.1524)
				)
			)
		)
		(duplicate_pad_numbers_are_jumpers no)
		(fp_line
			(start -0.508 -0.9398)
			(end -0.508 0.9398)
			(stroke
				(width 0.1524)
				(type default)
			)
			(layer "F.SilkS")
		)
		(fp_line
			(start 0.508 -0.9398)
			(end -0.508 -0.9398)
			(stroke
				(width 0.1524)
				(type default)
			)
			(layer "F.SilkS")
		)
		(fp_rect
			(start -0.508 0.9398)
			(end 0.508 -0.9398)
			(stroke
				(width 0)
				(type default)
			)
			(fill no)
			(layer "F.CrtYd")
		)
		(fp_rect
			(start -0.508 0.9398)
			(end 0.508 -0.9398)
			(stroke
				(width 0)
				(type default)
			)
			(fill no)
			(layer "F.Fab")
		)
		(pad "1" smd custom
			(at 0 -0.4445)
			(size 0.1397 0.1397)
			(layers "F.Cu" "F.Mask" "F.Paste")
			(net "EEPROM_A2")
			(options
				(clearance outline)
				(anchor circle)
			)
			(primitives
				(gr_poly
					(pts
						(arc
							(start -0.1778 -0.2794)
							(mid -0.249642 -0.249642)
							(end -0.2794 -0.1778)
						)
						(arc
							(start -0.2794 0.1778)
							(mid -0.249642 0.249642)
							(end -0.1778 0.2794)
						)
						(arc
							(start 0.1778 0.2794)
							(mid 0.249642 0.249642)
							(end 0.2794 0.1778)
						)
						(arc
							(start 0.2794 -0.1778)
							(mid 0.249642 -0.249642)
							(end 0.1778 -0.2794)
						)
					)
					(width 0)
					(fill yes)
				)
			)
		)
		(pad "2" smd custom
			(at 0 0.4445)
			(size 0.1397 0.1397)
			(layers "F.Cu" "F.Mask" "F.Paste")
			(net "GND")
			(options
				(clearance outline)
				(anchor circle)
			)
			(primitives
				(gr_poly
					(pts
						(arc
							(start -0.1778 -0.2794)
							(mid -0.249642 -0.249642)
							(end -0.2794 -0.1778)
						)
						(arc
							(start -0.2794 0.1778)
							(mid -0.249642 0.249642)
							(end -0.1778 0.2794)
						)
						(arc
							(start 0.1778 0.2794)
							(mid 0.249642 0.249642)
							(end 0.2794 0.1778)
						)
						(arc
							(start 0.2794 -0.1778)
							(mid 0.249642 -0.249642)
							(end 0.1778 -0.2794)
						)
					)
					(width 0)
					(fill yes)
				)
			)
		)
	)
	(footprint ""
		(layer "F.Cu")
		(at 333.248 -157.585918 180)
		(property "Reference" "R552"
			(at 0 0 180)
			(layer "F.SilkS")
			(hide yes)
			(effects
				(font
					(size 1.27 1.27)
				)
			)
		)
		(property "Value" "1KR2F-3-GP"
			(at 0.064008 -3.993896 180)
			(unlocked yes)
			(layer "F.Fab")
			(hide yes)
			(effects
				(font
					(size 1.016 1.016)
					(thickness 0.1524)
				)
			)
		)
		(property "Device Type" "R402H16"
			(at 0.064008 -5.517896 180)
			(unlocked yes)
			(layer "F.Fab")
			(hide yes)
			(effects
				(font
					(size 1.016 1.016)
					(thickness 0.1524)
				)
			)
		)
		(duplicate_pad_numbers_are_jumpers no)
		(fp_line
			(start 0.508 -0.9398)
			(end -0.508 -0.9398)
			(stroke
				(width 0.1524)
				(type default)
			)
			(layer "F.SilkS")
		)
		(fp_line
			(start -0.508 -0.9398)
			(end -0.508 0.9398)
			(stroke
				(width 0.1524)
				(type default)
			)
			(layer "F.SilkS")
		)
		(fp_rect
			(start -0.508 0.9398)
			(end 0.508 -0.9398)
			(stroke
				(width 0)
				(type default)
			)
			(fill no)
			(layer "F.CrtYd")
		)
		(fp_rect
			(start -0.508 0.9398)
			(end 0.508 -0.9398)
			(stroke
				(width 0)
				(type default)
			)
			(fill no)
			(layer "F.Fab")
		)
		(pad "1" smd custom
			(at 0 -0.4445 180)
			(size 0.1397 0.1397)
			(layers "F.Cu" "F.Mask" "F.Paste")
			(net "P3V3_STBY_A")
			(options
				(clearance outline)
				(anchor circle)
			)
			(primitives
				(gr_poly
					(pts
						(arc
							(start -0.1778 -0.2794)
							(mid -0.249642 -0.249642)
							(end -0.2794 -0.1778)
						)
						(arc
							(start -0.2794 0.1778)
							(mid -0.249642 0.249642)
							(end -0.1778 0.2794)
						)
						(arc
							(start 0.1778 0.2794)
							(mid 0.249642 0.249642)
							(end 0.2794 0.1778)
						)
						(arc
							(start 0.2794 -0.1778)
							(mid 0.249642 -0.249642)
							(end 0.1778 -0.2794)
						)
					)
					(width 0)
					(fill yes)
				)
			)
		)
		(pad "2" smd custom
			(at 0 0.4445 180)
			(size 0.1397 0.1397)
			(layers "F.Cu" "F.Mask" "F.Paste")
			(net "SW_PWR_R_HDD18")
			(options
				(clearance outline)
				(anchor circle)
			)
			(primitives
				(gr_poly
					(pts
						(arc
							(start -0.1778 -0.2794)
							(mid -0.249642 -0.249642)
							(end -0.2794 -0.1778)
						)
						(arc
							(start -0.2794 0.1778)
							(mid -0.249642 0.249642)
							(end -0.1778 0.2794)
						)
						(arc
							(start 0.1778 0.2794)
							(mid 0.249642 0.249642)
							(end 0.2794 0.1778)
						)
						(arc
							(start 0.2794 -0.1778)
							(mid 0.249642 -0.249642)
							(end 0.1778 -0.2794)
						)
					)
					(width 0)
					(fill yes)
				)
			)
		)
	)
	(footprint ""
		(layer "F.Cu")
		(at 220.599 -365.125)
		(property "Reference" "R173"
			(at 0 0 0)
			(layer "F.SilkS")
			(hide yes)
			(effects
				(font
					(size 1.27 1.27)
				)
			)
		)
		(property "Value" "4K7R2F-GP"
			(at 0.064008 -3.993896 0)
			(unlocked yes)
			(layer "F.Fab")
			(hide yes)
			(effects
				(font
					(size 1.016 1.016)
					(thickness 0.1524)
				)
			)
		)
		(property "Device Type" "R402H16"
			(at 0.064008 -5.517896 0)
			(unlocked yes)
			(layer "F.Fab")
			(hide yes)
			(effects
				(font
					(size 1.016 1.016)
					(thickness 0.1524)
				)
			)
		)
		(duplicate_pad_numbers_are_jumpers no)
		(fp_line
			(start -0.508 -0.9398)
			(end -0.508 0.9398)
			(stroke
				(width 0.1524)
				(type default)
			)
			(layer "F.SilkS")
		)
		(fp_line
			(start 0.508 -0.9398)
			(end -0.508 -0.9398)
			(stroke
				(width 0.1524)
				(type default)
			)
			(layer "F.SilkS")
		)
		(fp_rect
			(start -0.508 0.9398)
			(end 0.508 -0.9398)
			(stroke
				(width 0)
				(type default)
			)
			(fill no)
			(layer "F.CrtYd")
		)
		(fp_rect
			(start -0.508 0.9398)
			(end 0.508 -0.9398)
			(stroke
				(width 0)
				(type default)
			)
			(fill no)
			(layer "F.Fab")
		)
		(pad "1" smd custom
			(at 0 -0.4445)
			(size 0.1397 0.1397)
			(layers "F.Cu" "F.Mask" "F.Paste")
			(net "IO_EXP3_HDD_FAULT_INT_N")
			(options
				(clearance outline)
				(anchor circle)
			)
			(primitives
				(gr_poly
					(pts
						(arc
							(start -0.1778 -0.2794)
							(mid -0.249642 -0.249642)
							(end -0.2794 -0.1778)
						)
						(arc
							(start -0.2794 0.1778)
							(mid -0.249642 0.249642)
							(end -0.1778 0.2794)
						)
						(arc
							(start 0.1778 0.2794)
							(mid 0.249642 0.249642)
							(end 0.2794 0.1778)
						)
						(arc
							(start 0.2794 -0.1778)
							(mid 0.249642 -0.249642)
							(end 0.1778 -0.2794)
						)
					)
					(width 0)
					(fill yes)
				)
			)
		)
		(pad "2" smd custom
			(at 0 0.4445)
			(size 0.1397 0.1397)
			(layers "F.Cu" "F.Mask" "F.Paste")
			(net "P3V3_STBY_B")
			(options
				(clearance outline)
				(anchor circle)
			)
			(primitives
				(gr_poly
					(pts
						(arc
							(start -0.1778 -0.2794)
							(mid -0.249642 -0.249642)
							(end -0.2794 -0.1778)
						)
						(arc
							(start -0.2794 0.1778)
							(mid -0.249642 0.249642)
							(end -0.1778 0.2794)
						)
						(arc
							(start 0.1778 0.2794)
							(mid 0.249642 0.249642)
							(end 0.2794 0.1778)
						)
						(arc
							(start 0.2794 -0.1778)
							(mid 0.249642 -0.249642)
							(end 0.1778 -0.2794)
						)
					)
					(width 0)
					(fill yes)
				)
			)
		)
	)
	(footprint ""
		(layer "F.Cu")
		(at 143.999966 -209.399886)
		(property "Reference" "FLED5"
			(at 0 0 0)
			(layer "F.SilkS")
			(hide yes)
			(effects
				(font
					(size 1.27 1.27)
				)
			)
		)
		(property "Value" "LED-BY-19-GP"
			(at -2.132076 1.414018 0)
			(unlocked yes)
			(layer "F.Fab")
			(hide yes)
			(effects
				(font
					(size 1.016 1.016)
					(thickness 0.1524)
				)
			)
		)
		(property "Device Type" "LED-1615-4PH26"
			(at -2.132076 -0.109982 0)
			(unlocked yes)
			(layer "F.Fab")
			(hide yes)
			(effects
				(font
					(size 1.016 1.016)
					(thickness 0.1524)
				)
			)
		)
		(duplicate_pad_numbers_are_jumpers no)
		(fp_line
			(start -1.2954 0.254)
			(end -1.2954 1.6002)
			(stroke
				(width 0.508)
				(type default)
			)
			(layer "F.SilkS")
		)
		(fp_line
			(start -1.2954 1.6002)
			(end 1.2954 1.6002)
			(stroke
				(width 0.508)
				(type default)
			)
			(layer "F.SilkS")
		)
		(fp_line
			(start -1.1176 -1.4224)
			(end 1.1176 -1.4224)
			(stroke
				(width 0.1524)
				(type default)
			)
			(layer "F.SilkS")
		)
		(fp_line
			(start -1.1176 1.4224)
			(end -1.1176 -1.4224)
			(stroke
				(width 0.1524)
				(type default)
			)
			(layer "F.SilkS")
		)
		(fp_line
			(start 1.1176 -1.4224)
			(end 1.1176 1.4224)
			(stroke
				(width 0.1524)
				(type default)
			)
			(layer "F.SilkS")
		)
		(fp_line
			(start 1.1176 1.4224)
			(end -1.1176 1.4224)
			(stroke
				(width 0.1524)
				(type default)
			)
			(layer "F.SilkS")
		)
		(fp_line
			(start 1.2954 1.6002)
			(end 1.2954 0.254)
			(stroke
				(width 0.508)
				(type default)
			)
			(layer "F.SilkS")
		)
		(fp_rect
			(start -0.7493 0.8001)
			(end 0.7493 -0.8001)
			(stroke
				(width 0)
				(type default)
			)
			(fill no)
			(layer "F.CrtYd")
		)
		(fp_poly
			(pts
				(xy -1.3716 1.6764) (xy -1.3716 -1.6764) (xy 1.3716 -1.6764) (xy 1.3716 0.0635) (xy 0.7493 0.0635)
				(xy 0.7493 -0.8001) (xy -0.7493 -0.8001) (xy -0.7493 0.8001) (xy 0.7493 0.8001) (xy 0.7493 0.0762)
				(xy 1.3716 0.0762) (xy 1.3716 1.6764)
			)
			(stroke
				(width 0)
				(type default)
			)
			(fill no)
			(layer "F.CrtYd")
		)
		(fp_rect
			(start -1.3716 1.6764)
			(end 1.3716 -1.6764)
			(stroke
				(width 0)
				(type default)
			)
			(fill no)
			(layer "F.Fab")
		)
		(pad "1" smd rect
			(at 0.50038 -0.73025)
			(size 0.7112 0.8636)
			(layers "F.Cu" "F.Mask" "F.Paste")
			(net "DRV_ACT_4")
		)
		(pad "2" smd rect
			(at -0.50038 -0.73025)
			(size 0.7112 0.8636)
			(layers "F.Cu" "F.Mask" "F.Paste")
			(net "FLT_HDD4")
		)
		(pad "3" smd rect
			(at 0.50038 0.73025)
			(size 0.7112 0.8636)
			(layers "F.Cu" "F.Mask" "F.Paste")
			(net "DRV_ACT_4_N")
		)
		(pad "4" smd rect
			(at -0.50038 0.73025)
			(size 0.7112 0.8636)
			(layers "F.Cu" "F.Mask" "F.Paste")
			(net "FLT_HDD4_N")
		)
	)
	(footprint ""
		(layer "F.Cu")
		(at 237.492286 -251.907802 90)
		(property "Reference" "C9"
			(at 0 0 90)
			(layer "F.SilkS")
			(hide yes)
			(effects
				(font
					(size 1.27 1.27)
				)
			)
		)
		(property "Value" "SC1U16V3KX-5GP"
			(at 0 -2.8194 90)
			(unlocked yes)
			(layer "F.Fab")
			(hide yes)
			(effects
				(font
					(size 1.016 1.016)
					(thickness 0.1524)
				)
			)
		)
		(property "Device Type" "C603H36"
			(at 0 -4.3434 90)
			(unlocked yes)
			(layer "F.Fab")
			(hide yes)
			(effects
				(font
					(size 1.016 1.016)
					(thickness 0.1524)
				)
			)
		)
		(duplicate_pad_numbers_are_jumpers no)
		(fp_line
			(start 0.508 0)
			(end -0.508 0)
			(stroke
				(width 0.2032)
				(type default)
			)
			(layer "F.SilkS")
		)
		(fp_rect
			(start -0.5842 1.3335)
			(end 0.5842 -1.3335)
			(stroke
				(width 0)
				(type default)
			)
			(fill no)
			(layer "F.CrtYd")
		)
		(fp_rect
			(start -0.5842 1.3335)
			(end 0.5842 -1.3335)
			(stroke
				(width 0)
				(type default)
			)
			(fill no)
			(layer "F.Fab")
		)
		(pad "1" smd custom
			(at 0 -0.762 90)
			(size 0.2159 0.2159)
			(layers "F.Cu" "F.Mask" "F.Paste")
			(net "P3V3_STBY_A")
			(options
				(clearance outline)
				(anchor circle)
			)
			(primitives
				(gr_poly
					(pts
						(arc
							(start -0.3302 -0.4318)
							(mid -0.402042 -0.402042)
							(end -0.4318 -0.3302)
						)
						(arc
							(start -0.4318 0.3302)
							(mid -0.402042 0.402042)
							(end -0.3302 0.4318)
						)
						(arc
							(start 0.3302 0.4318)
							(mid 0.402042 0.402042)
							(end 0.4318 0.3302)
						)
						(arc
							(start 0.4318 -0.3302)
							(mid 0.402042 -0.402042)
							(end 0.3302 -0.4318)
						)
					)
					(width 0)
					(fill yes)
				)
			)
		)
		(pad "2" smd custom
			(at 0 0.762 90)
			(size 0.2159 0.2159)
			(layers "F.Cu" "F.Mask" "F.Paste")
			(net "GND")
			(options
				(clearance outline)
				(anchor circle)
			)
			(primitives
				(gr_poly
					(pts
						(arc
							(start -0.3302 -0.4318)
							(mid -0.402042 -0.402042)
							(end -0.4318 -0.3302)
						)
						(arc
							(start -0.4318 0.3302)
							(mid -0.402042 0.402042)
							(end -0.3302 0.4318)
						)
						(arc
							(start 0.3302 0.4318)
							(mid 0.402042 0.402042)
							(end 0.4318 0.3302)
						)
						(arc
							(start 0.4318 -0.3302)
							(mid 0.402042 -0.402042)
							(end 0.3302 -0.4318)
						)
					)
					(width 0)
					(fill yes)
				)
			)
		)
	)
)
